# BASEBOARD_FAB2 (Tioga Pass) — schematic netlist excerpt (pin names and nets, part order shuffled) for the footprints in the layout excerpt that follows; sources: Cadence DE-HDL packaged netlist, KiCad conversion of Wiwynn_Tioga_Pass_MB.brd

C6W14  CAP_A  0.1UF 16V 10% X7R  pkg 0402V  page 164 : A = P3V3_STBY ; B = GND
R8B7  RES  1.8K 1% CHIP  pkg 0402  page 91 : A = PVPP_ABC ; B = SMB_HFI0_CPU0_LVC2_SDA
C7B30  CAP  0.1UF 25V 10% X7R  pkg 0603LF  page 232 : A = VR_PVPP_DEF_PHASE ; B = VR_PVPP_DEF_BOOT_R

(kicad_pcb
	(version 20260206)
	(generator "pcbnew")
	(generator_version "10.0")
	(general
		(thickness 1.6)
		(legacy_teardrops no)
	)
	(paper "A4")
	(title_block
		(title "Wiwynn_Tioga_Pass_MB.brd")
		(comment 1 "Tioga Pass / footprints 1400-1402 of 4770")
	)
	(layers
		(0 "F.Cu" signal "TOP")
		(4 "In1.Cu" signal "L2GND")
		(6 "In2.Cu" signal "L3")
		(8 "In3.Cu" signal "L4GND")
		(10 "In4.Cu" signal "L5")
		(12 "In5.Cu" signal "L6GND")
		(14 "In6.Cu" signal "L7VCC")
		(16 "In7.Cu" signal "L8VCC")
		(18 "In8.Cu" signal "L9GND")
		(20 "In9.Cu" signal "L10")
		(22 "In10.Cu" signal "L11GND")
		(24 "In11.Cu" signal "L12")
		(26 "In12.Cu" signal "L13GND")
		(2 "B.Cu" signal "BOTTOM")
		(9 "F.Adhes" user "F.Adhesive")
		(11 "B.Adhes" user "B.Adhesive")
		(13 "F.Paste" user "Package Geometry/Pastemask Top")
		(15 "B.Paste" user "Package Geometry/Pastemask Bottom")
		(5 "F.SilkS" user "Ref Des/Silkscreen Top")
		(7 "B.SilkS" user "Ref Des/Silkscreen Bottom")
		(1 "F.Mask" user "Board Geometry/Soldermask Top")
		(3 "B.Mask" user "Board Geometry/Soldermask Bottom")
		(17 "Dwgs.User" user "User.Drawings")
		(19 "Cmts.User" user "User.Comments")
		(21 "Eco1.User" user "User.Eco1")
		(23 "Eco2.User" user "User.Eco2")
		(25 "Edge.Cuts" user "Board Geometry/Outline")
		(27 "Margin" user)
		(31 "F.CrtYd" user "Package Geometry/Place Bound Top")
		(29 "B.CrtYd" user "Package Geometry/Place Bound Bottom")
		(35 "F.Fab" user "Ref Des/Assembly Top")
		(33 "B.Fab" user "Ref Des/Assembly Bottom")
	)
	(footprint ""
		(layer "F.Cu")
		(at 426.5295 -129.794 -90)
		(property "Reference" "R8B7"
			(at 0 0 270)
			(layer "F.SilkS")
			(hide yes)
			(effects
				(font
					(size 1.27 1.27)
				)
			)
		)
		(property "Value" ""
			(at 0 0 270)
			(layer "F.Fab")
			(effects
				(font
					(size 1.27 1.27)
				)
			)
		)
		(duplicate_pad_numbers_are_jumpers no)
		(fp_poly
			(pts
				(xy -0.2794 -0.1016) (xy 0.2794 -0.1016) (xy 0.2794 0.9906) (xy -0.2794 0.9906)
			)
			(stroke
				(width 0)
				(type default)
			)
			(fill no)
			(layer "F.CrtYd")
		)
		(fp_line
			(start -0.2794 0.9906)
			(end 0.2794 0.9906)
			(stroke
				(width 0.1)
				(type default)
			)
			(layer "F.Fab")
		)
		(fp_line
			(start 0.2794 0.9906)
			(end 0.2794 -0.1016)
			(stroke
				(width 0.1)
				(type default)
			)
			(layer "F.Fab")
		)
		(fp_line
			(start -0.2794 -0.1016)
			(end -0.2794 0.9906)
			(stroke
				(width 0.1)
				(type default)
			)
			(layer "F.Fab")
		)
		(fp_line
			(start 0.2794 -0.1016)
			(end -0.2794 -0.1016)
			(stroke
				(width 0.1)
				(type default)
			)
			(layer "F.Fab")
		)
		(pad "1" smd rect
			(at 0 0 270)
			(size 0.508 0.508)
			(layers "F.Cu" "F.Mask" "F.Paste")
			(net "PVPP_ABC")
		)
		(pad "2" smd rect
			(at 0 0.889 270)
			(size 0.508 0.508)
			(layers "F.Cu" "F.Mask" "F.Paste")
			(net "SMB_HFI0_CPU0_LVC2_SDA")
		)
		(zone
			(layer "F.Cu")
			(hatch none 0.5)
			(connect_pads
				(clearance 0)
			)
			(min_thickness 0.25)
			(keepout
				(tracks not_allowed)
				(vias allowed)
				(pads allowed)
				(copperpour not_allowed)
				(footprints allowed)
			)
			(placement
				(enabled no)
				(sheetname "")
			)
			(fill
				(thermal_gap 0.5)
				(thermal_bridge_width 0.5)
				(island_removal_mode 0)
			)
			(polygon
				(pts
					(xy 425.8945 -130.048) (xy 425.8945 -129.54) (xy 426.2755 -129.54) (xy 426.2755 -130.048)
				)
			)
		)
		(zone
			(layer "F.Cu")
			(hatch none 0.5)
			(connect_pads
				(clearance 0)
			)
			(min_thickness 0.25)
			(keepout
				(tracks allowed)
				(vias not_allowed)
				(pads allowed)
				(copperpour not_allowed)
				(footprints allowed)
			)
			(placement
				(enabled no)
				(sheetname "")
			)
			(fill
				(thermal_gap 0.5)
				(thermal_bridge_width 0.5)
				(island_removal_mode 0)
			)
			(polygon
				(pts
					(xy 426.2755 -130.048) (xy 426.2755 -129.54) (xy 425.8945 -129.54) (xy 425.8945 -130.048)
				)
			)
		)
	)
	(footprint ""
		(layer "F.Cu")
		(at 433.1335 -11.4046 180)
		(property "Reference" "C6W14"
			(at -0.8382 -0.67818 180)
			(unlocked yes)
			(layer "F.SilkS")
			(effects
				(font
					(size 0.4064 0.254)
					(thickness 0.1524)
				)
				(justify left)
			)
		)
		(property "Value" ""
			(at 0 0 180)
			(layer "F.Fab")
			(effects
				(font
					(size 1.27 1.27)
				)
			)
		)
		(duplicate_pad_numbers_are_jumpers no)
		(fp_poly
			(pts
				(xy 0.3048 -0.1016) (xy 0.3048 0.9906) (xy -0.3048 0.9906) (xy -0.3048 -0.1016)
			)
			(stroke
				(width 0)
				(type default)
			)
			(fill no)
			(layer "F.CrtYd")
		)
		(fp_line
			(start 0.3048 0.9906)
			(end 0.3048 -0.1016)
			(stroke
				(width 0.1)
				(type default)
			)
			(layer "F.Fab")
		)
		(fp_line
			(start 0.3048 -0.1016)
			(end -0.3048 -0.1016)
			(stroke
				(width 0.1)
				(type default)
			)
			(layer "F.Fab")
		)
		(fp_line
			(start -0.3048 0.9906)
			(end 0.3048 0.9906)
			(stroke
				(width 0.1)
				(type default)
			)
			(layer "F.Fab")
		)
		(fp_line
			(start -0.3048 -0.1016)
			(end -0.3048 0.9906)
			(stroke
				(width 0.1)
				(type default)
			)
			(layer "F.Fab")
		)
		(pad "1" smd rect
			(at 0 0 180)
			(size 0.508 0.508)
			(layers "F.Cu" "F.Mask" "F.Paste")
			(net "P3V3_STBY")
		)
		(pad "2" smd rect
			(at 0 0.889 180)
			(size 0.508 0.508)
			(layers "F.Cu" "F.Mask" "F.Paste")
			(net "GND")
		)
		(zone
			(layer "F.Cu")
			(hatch none 0.5)
			(connect_pads
				(clearance 0)
			)
			(min_thickness 0.25)
			(keepout
				(tracks not_allowed)
				(vias allowed)
				(pads allowed)
				(copperpour not_allowed)
				(footprints allowed)
			)
			(placement
				(enabled no)
				(sheetname "")
			)
			(fill
				(thermal_gap 0.5)
				(thermal_bridge_width 0.5)
				(island_removal_mode 0)
			)
			(polygon
				(pts
					(xy 433.3875 -12.0396) (xy 432.8795 -12.0396) (xy 432.8795 -11.6586) (xy 433.3875 -11.6586)
				)
			)
		)
		(zone
			(layer "F.Cu")
			(hatch none 0.5)
			(connect_pads
				(clearance 0)
			)
			(min_thickness 0.25)
			(keepout
				(tracks allowed)
				(vias not_allowed)
				(pads allowed)
				(copperpour not_allowed)
				(footprints allowed)
			)
			(placement
				(enabled no)
				(sheetname "")
			)
			(fill
				(thermal_gap 0.5)
				(thermal_bridge_width 0.5)
				(island_removal_mode 0)
			)
			(polygon
				(pts
					(xy 433.3875 -11.6586) (xy 432.8795 -11.6586) (xy 432.8795 -12.0396) (xy 433.3875 -12.0396)
				)
			)
		)
	)
	(footprint ""
		(layer "F.Cu")
		(at 336.509868 -130.455162 90)
		(property "Reference" "C7B30"
			(at 0 0 90)
			(layer "F.SilkS")
			(hide yes)
			(effects
				(font
					(size 1.27 1.27)
				)
			)
		)
		(property "Value" ""
			(at 0 0 90)
			(layer "F.Fab")
			(effects
				(font
					(size 1.27 1.27)
				)
			)
		)
		(duplicate_pad_numbers_are_jumpers no)
		(fp_poly
			(pts
				(xy -0.4953 -0.2032) (xy 0.4953 -0.2032) (xy 0.4953 1.6002) (xy -0.4953 1.6002)
			)
			(stroke
				(width 0)
				(type default)
			)
			(fill no)
			(layer "F.CrtYd")
		)
		(fp_line
			(start 0.4953 -0.2032)
			(end 0.4953 1.6002)
			(stroke
				(width 0.1)
				(type default)
			)
			(layer "F.Fab")
		)
		(fp_line
			(start -0.4953 -0.2032)
			(end 0.4953 -0.2032)
			(stroke
				(width 0.1)
				(type default)
			)
			(layer "F.Fab")
		)
		(fp_line
			(start 0.4953 1.6002)
			(end -0.4953 1.6002)
			(stroke
				(width 0.1)
				(type default)
			)
			(layer "F.Fab")
		)
		(fp_line
			(start -0.4953 1.6002)
			(end -0.4953 -0.2032)
			(stroke
				(width 0.1)
				(type default)
			)
			(layer "F.Fab")
		)
		(pad "1" smd rect
			(at 0 0 90)
			(size 0.762 0.889)
			(layers "F.Cu" "F.Mask" "F.Paste")
			(net "VR_PVPP_DEF_PHASE")
		)
		(pad "2" smd rect
			(at 0 1.397 90)
			(size 0.762 0.889)
			(layers "F.Cu" "F.Mask" "F.Paste")
			(net "VR_PVPP_DEF_BOOT_R")
		)
		(zone
			(layer "F.Cu")
			(hatch none 0.5)
			(connect_pads
				(clearance 0)
			)
			(min_thickness 0.25)
			(keepout
				(tracks not_allowed)
				(vias allowed)
				(pads allowed)
				(copperpour not_allowed)
				(footprints allowed)
			)
			(placement
				(enabled no)
				(sheetname "")
			)
			(fill
				(thermal_gap 0.5)
				(thermal_bridge_width 0.5)
				(island_removal_mode 0)
			)
			(polygon
				(pts
					(xy 336.954368 -130.074162) (xy 336.954368 -130.836162) (xy 337.462368 -130.836162) (xy 337.462368 -130.074162)
				)
			)
		)
	)
)
